# BASEBOARD_FAB2 (Tioga Pass) — schematic netlist excerpt (pin names and nets, part order shuffled) for the footprints in the layout excerpt that follows; sources: Cadence DE-HDL packaged netlist, KiCad conversion of Wiwynn_Tioga_Pass_MB.brd

EU9E1  SPRINGVILLE  IC  pkg SM1  page 139
  LAN_PWR_GOOD  = PU_SPRV_LAN_PWR_GOOD
  NC_SI_CLK_IN  = CLK_50M_CKMNG_SPRVLLE
  NC_SI_CRS_DV  = RMII_BMC_PCH_SPRNGVLLE_CRSDV_R
  JTAG_TDO  = PU_JTAG_SPRV_TDO
  NC_SI_RXD1  = RMII_SPRNGVLLE_BMC_PCH_RXD1_R
  NC_SI_RXD0  = RMII_SPRNGVLLE_BMC_PCH_RXD0_R
  NC_SI_TX_EN  = RMII_BMC_PCH_SPRNGVLLE_TXEN
  NC_SI_TXD1  = RMII_BMC_PCH_SPRNGVLLE_TXD1
  NC_SI_TXD0  = RMII_BMC_PCH_SPRNGVLLE_TXD0
  VDD3P3(4)  = P3V3_STBY
  VDD0P9(2)  = P0V9_LAN
  NVM_SI  = SPI_NIC_MOSI_R
  NVM_SK  = SPI_NIC_SCLK_R
  NVM_SO  = SPI_NIC_MISO
  NVM_CS_N  = SPI_NIC_CS_R_N
  PE_WAKE_N  = FM_PE_SPRV_WAKE_N
  PE_RST_N  = RST_PLTRST_SPRV_R_N
  JTAG_TMS  = PU_JTAG_SPRV_TMS
  JTAG_CLK  = PU_JTAG_SPRV_TCK
  PE_TN  = PE_PCH_SPRV_RX_DN
  PE_TP  = PE_PCH_SPRV_RX_DP
  NC  = NC
  PE_RN  = PE_PCH_SPRV_TX_C_DN
  PE_RP  = PE_PCH_SPRV_TX_C_DP
  PECLKN  = CLK_100M_SPRV_DN
  PECLKP  = CLK_100M_SPRV_DP
  VDD3P3(3)  = P3V3_STBY
  DEV_OFF_N  = PU_DEV_OFF_N
  JTAG_TDI  = PU_JTAG_SPRV_TDI
  LED1  = LED_LAN_1_N
  LED0  = LED_LAN_0_N
  VDD0P9(1)  = P0V9_LAN
  LED2  = LED_LAN_2_N
  SMB_CLK  = SMB_SPRINGVILLE_STBY_LVC3_SCL
  SMB_ALRT_N  = IRQ_LOM_ALERT_N
  SMB_DATA  = SMB_SPRINGVILLE_STBY_LVC3_SDA
  CBOT  = A_CBOT
  VDD0P9_OUT  = P0V9_LAN_I210
  VDD1P5_OUT  = P1V5_LAN
  CTOP  = A_CTOP
  VDD3P3(2)  = P3V3_STBY
  VDD0P9(3)  = P0V9_LAN
  NC_SI_ARB_IN  = RMII_PCH_SPRNGVLLE_ARB_OUT
  NC_SI_ARB_OUT  = RMII_PCH_SPRNGVLLE_ARB_IN_R
  XTAL2  = XTAL_25MHZ_OUT
  XTAL1  = XTAL_25MHZ_IN_R
  VDD1P5(1)  = P1V5_LAN
  RSET  = PD_SPRV_RSET
  MDI_MINUS3_SERN  = NIC_SER_N_MDI_3_DN
  MDI_PLUS3_SERP  = NIC_SER_P_MDI_3_DP
  VDD3P3(1)  = P3V3_STBY_P1V5_LAN_I210
  MDI_MINUS2_SETN  = NIC_SET_N_MDI_2_DN
  MDI_PLUS2_SETP  = NIC_SET_P_MDI_2_DP
  MDI_MINUS1_SRDS_SIG_DET  = NIC_MDI_SPRV_RJ45_1_DN
  MDI_PLUS1_SFP_I2C_CLK  = NIC_MDI_SPRV_RJ45_1_DP
  VDD1P5(0)  = P1V5_LAN_I210
  MDI_MINUS0_SFP_I2C_DATA  = NIC_MDI_SPRV_RJ45_0_DN
  MDI_PLUS0_NC  = NIC_MDI_SPRV_RJ45_0_DP
  VDD0P9(0)  = P0V9_LAN
  SDP3  = TP_SPRV_SDP3
  SDP1_PCIE_DIS_SDP1  = FM_1GB_LOM_DISABLE_N
  SDP2  = TP_SPRV_SDP2
  SDP0  = TP_SPRV_SDP0
  VDD3P3(0)  = P3V3_STBY
  GND  = GND

(kicad_pcb
	(version 20260206)
	(generator "pcbnew")
	(generator_version "10.0")
	(general
		(thickness 1.6)
		(legacy_teardrops no)
	)
	(paper "A4")
	(title_block
		(title "Wiwynn_Tioga_Pass_MB.brd")
		(comment 1 "Tioga Pass / footprint 1033 of 4770 (EU9E1), pads 1-17 of 65")
	)
	(layers
		(0 "F.Cu" signal "TOP")
		(4 "In1.Cu" signal "L2GND")
		(6 "In2.Cu" signal "L3")
		(8 "In3.Cu" signal "L4GND")
		(10 "In4.Cu" signal "L5")
		(12 "In5.Cu" signal "L6GND")
		(14 "In6.Cu" signal "L7VCC")
		(16 "In7.Cu" signal "L8VCC")
		(18 "In8.Cu" signal "L9GND")
		(20 "In9.Cu" signal "L10")
		(22 "In10.Cu" signal "L11GND")
		(24 "In11.Cu" signal "L12")
		(26 "In12.Cu" signal "L13GND")
		(2 "B.Cu" signal "BOTTOM")
		(9 "F.Adhes" user "F.Adhesive")
		(11 "B.Adhes" user "B.Adhesive")
		(13 "F.Paste" user "Package Geometry/Pastemask Top")
		(15 "B.Paste" user "Package Geometry/Pastemask Bottom")
		(5 "F.SilkS" user "Ref Des/Silkscreen Top")
		(7 "B.SilkS" user "Ref Des/Silkscreen Bottom")
		(1 "F.Mask" user "Board Geometry/Soldermask Top")
		(3 "B.Mask" user "Board Geometry/Soldermask Bottom")
		(17 "Dwgs.User" user "User.Drawings")
		(19 "Cmts.User" user "User.Comments")
		(21 "Eco1.User" user "User.Eco1")
		(23 "Eco2.User" user "User.Eco2")
		(25 "Edge.Cuts" user "Board Geometry/Outline")
		(27 "Margin" user)
		(31 "F.CrtYd" user "Package Geometry/Place Bound Top")
		(29 "B.CrtYd" user "Package Geometry/Place Bound Bottom")
		(35 "F.Fab" user "Ref Des/Assembly Top")
		(33 "B.Fab" user "Ref Des/Assembly Bottom")
	)
	(footprint ""
		(layer "F.Cu")
		(at 484.251 -43.9674 180)
		(property "Reference" "EU9E1"
			(at 7.2644 -5.49529 0)
			(unlocked yes)
			(layer "F.SilkS")
			(effects
				(font
					(size 0.7874 0.5842)
					(thickness 0.1524)
				)
				(justify left)
			)
		)
		(property "Value" ""
			(at 0 0 180)
			(layer "F.Fab")
			(effects
				(font
					(size 1.27 1.27)
				)
			)
		)
		(duplicate_pad_numbers_are_jumpers no)
		(pad "1" smd custom
			(at -4.3688 -3.750056 180)
			(size 0.0762 0.0762)
			(layers "F.Cu" "F.Mask" "F.Paste")
			(net "PU_SPRV_LAN_PWR_GOOD")
			(options
				(clearance outline)
				(anchor circle)
			)
			(primitives
				(gr_poly
					(pts
						(xy -0.381 -0.1524)
						(arc
							(start 0.2286 -0.1524)
							(mid 0.381 0)
							(end 0.2286 0.1524)
						)
						(xy -0.381 0.1524)
					)
					(width 0)
					(fill yes)
				)
			)
		)
		(pad "2" smd custom
			(at -4.3688 -3.24993 180)
			(size 0.0762 0.0762)
			(layers "F.Cu" "F.Mask" "F.Paste")
			(net "CLK_50M_CKMNG_SPRVLLE")
			(options
				(clearance outline)
				(anchor circle)
			)
			(primitives
				(gr_poly
					(pts
						(xy -0.381 -0.1524)
						(arc
							(start 0.2286 -0.1524)
							(mid 0.381 0)
							(end 0.2286 0.1524)
						)
						(xy -0.381 0.1524)
					)
					(width 0)
					(fill yes)
				)
			)
		)
		(pad "3" smd custom
			(at -4.3688 -2.750058 180)
			(size 0.0762 0.0762)
			(layers "F.Cu" "F.Mask" "F.Paste")
			(net "RMII_BMC_PCH_SPRNGVLLE_CRSDV_R")
			(options
				(clearance outline)
				(anchor circle)
			)
			(primitives
				(gr_poly
					(pts
						(xy -0.381 -0.1524)
						(arc
							(start 0.2286 -0.1524)
							(mid 0.381 0)
							(end 0.2286 0.1524)
						)
						(xy -0.381 0.1524)
					)
					(width 0)
					(fill yes)
				)
			)
		)
		(pad "4" smd custom
			(at -4.3688 -2.249932 180)
			(size 0.0762 0.0762)
			(layers "F.Cu" "F.Mask" "F.Paste")
			(net "PU_JTAG_SPRV_TDO")
			(options
				(clearance outline)
				(anchor circle)
			)
			(primitives
				(gr_poly
					(pts
						(xy -0.381 -0.1524)
						(arc
							(start 0.2286 -0.1524)
							(mid 0.381 0)
							(end 0.2286 0.1524)
						)
						(xy -0.381 0.1524)
					)
					(width 0)
					(fill yes)
				)
			)
		)
		(pad "5" smd custom
			(at -4.3688 -1.75006 180)
			(size 0.0762 0.0762)
			(layers "F.Cu" "F.Mask" "F.Paste")
			(net "RMII_SPRNGVLLE_BMC_PCH_RXD1_R")
			(options
				(clearance outline)
				(anchor circle)
			)
			(primitives
				(gr_poly
					(pts
						(xy -0.381 -0.1524)
						(arc
							(start 0.2286 -0.1524)
							(mid 0.381 0)
							(end 0.2286 0.1524)
						)
						(xy -0.381 0.1524)
					)
					(width 0)
					(fill yes)
				)
			)
		)
		(pad "6" smd custom
			(at -4.3688 -1.249934 180)
			(size 0.0762 0.0762)
			(layers "F.Cu" "F.Mask" "F.Paste")
			(net "RMII_SPRNGVLLE_BMC_PCH_RXD0_R")
			(options
				(clearance outline)
				(anchor circle)
			)
			(primitives
				(gr_poly
					(pts
						(xy -0.381 -0.1524)
						(arc
							(start 0.2286 -0.1524)
							(mid 0.381 0)
							(end 0.2286 0.1524)
						)
						(xy -0.381 0.1524)
					)
					(width 0)
					(fill yes)
				)
			)
		)
		(pad "7" smd custom
			(at -4.3688 -0.750062 180)
			(size 0.0762 0.0762)
			(layers "F.Cu" "F.Mask" "F.Paste")
			(net "RMII_BMC_PCH_SPRNGVLLE_TXEN")
			(options
				(clearance outline)
				(anchor circle)
			)
			(primitives
				(gr_poly
					(pts
						(xy -0.381 -0.1524)
						(arc
							(start 0.2286 -0.1524)
							(mid 0.381 0)
							(end 0.2286 0.1524)
						)
						(xy -0.381 0.1524)
					)
					(width 0)
					(fill yes)
				)
			)
		)
		(pad "8" smd custom
			(at -4.3688 -0.249936 180)
			(size 0.0762 0.0762)
			(layers "F.Cu" "F.Mask" "F.Paste")
			(net "RMII_BMC_PCH_SPRNGVLLE_TXD1")
			(options
				(clearance outline)
				(anchor circle)
			)
			(primitives
				(gr_poly
					(pts
						(xy -0.381 -0.1524)
						(arc
							(start 0.2286 -0.1524)
							(mid 0.381 0)
							(end 0.2286 0.1524)
						)
						(xy -0.381 0.1524)
					)
					(width 0)
					(fill yes)
				)
			)
		)
		(pad "9" smd custom
			(at -4.3688 0.249936 180)
			(size 0.0762 0.0762)
			(layers "F.Cu" "F.Mask" "F.Paste")
			(net "RMII_BMC_PCH_SPRNGVLLE_TXD0")
			(options
				(clearance outline)
				(anchor circle)
			)
			(primitives
				(gr_poly
					(pts
						(xy -0.381 -0.1524)
						(arc
							(start 0.2286 -0.1524)
							(mid 0.381 0)
							(end 0.2286 0.1524)
						)
						(xy -0.381 0.1524)
					)
					(width 0)
					(fill yes)
				)
			)
		)
		(pad "10" smd custom
			(at -4.3688 0.750062 180)
			(size 0.0762 0.0762)
			(layers "F.Cu" "F.Mask" "F.Paste")
			(net "P3V3_STBY")
			(options
				(clearance outline)
				(anchor circle)
			)
			(primitives
				(gr_poly
					(pts
						(xy -0.381 -0.1524)
						(arc
							(start 0.2286 -0.1524)
							(mid 0.381 0)
							(end 0.2286 0.1524)
						)
						(xy -0.381 0.1524)
					)
					(width 0)
					(fill yes)
				)
			)
		)
		(pad "11" smd custom
			(at -4.3688 1.249934 180)
			(size 0.0762 0.0762)
			(layers "F.Cu" "F.Mask" "F.Paste")
			(net "P0V9_LAN")
			(options
				(clearance outline)
				(anchor circle)
			)
			(primitives
				(gr_poly
					(pts
						(xy -0.381 -0.1524)
						(arc
							(start 0.2286 -0.1524)
							(mid 0.381 0)
							(end 0.2286 0.1524)
						)
						(xy -0.381 0.1524)
					)
					(width 0)
					(fill yes)
				)
			)
		)
		(pad "12" smd custom
			(at -4.3688 1.75006 180)
			(size 0.0762 0.0762)
			(layers "F.Cu" "F.Mask" "F.Paste")
			(net "SPI_NIC_MOSI_R")
			(options
				(clearance outline)
				(anchor circle)
			)
			(primitives
				(gr_poly
					(pts
						(xy -0.381 -0.1524)
						(arc
							(start 0.2286 -0.1524)
							(mid 0.381 0)
							(end 0.2286 0.1524)
						)
						(xy -0.381 0.1524)
					)
					(width 0)
					(fill yes)
				)
			)
		)
		(pad "13" smd custom
			(at -4.3688 2.249932 180)
			(size 0.0762 0.0762)
			(layers "F.Cu" "F.Mask" "F.Paste")
			(net "SPI_NIC_SCLK_R")
			(options
				(clearance outline)
				(anchor circle)
			)
			(primitives
				(gr_poly
					(pts
						(xy -0.381 -0.1524)
						(arc
							(start 0.2286 -0.1524)
							(mid 0.381 0)
							(end 0.2286 0.1524)
						)
						(xy -0.381 0.1524)
					)
					(width 0)
					(fill yes)
				)
			)
		)
		(pad "14" smd custom
			(at -4.3688 2.750058 180)
			(size 0.0762 0.0762)
			(layers "F.Cu" "F.Mask" "F.Paste")
			(net "SPI_NIC_MISO")
			(options
				(clearance outline)
				(anchor circle)
			)
			(primitives
				(gr_poly
					(pts
						(xy -0.381 -0.1524)
						(arc
							(start 0.2286 -0.1524)
							(mid 0.381 0)
							(end 0.2286 0.1524)
						)
						(xy -0.381 0.1524)
					)
					(width 0)
					(fill yes)
				)
			)
		)
		(pad "15" smd custom
			(at -4.3688 3.24993 180)
			(size 0.0762 0.0762)
			(layers "F.Cu" "F.Mask" "F.Paste")
			(net "SPI_NIC_CS_R_N")
			(options
				(clearance outline)
				(anchor circle)
			)
			(primitives
				(gr_poly
					(pts
						(xy -0.381 -0.1524)
						(arc
							(start 0.2286 -0.1524)
							(mid 0.381 0)
							(end 0.2286 0.1524)
						)
						(xy -0.381 0.1524)
					)
					(width 0)
					(fill yes)
				)
			)
		)
		(pad "16" smd custom
			(at -4.3688 3.750056 180)
			(size 0.0762 0.0762)
			(layers "F.Cu" "F.Mask" "F.Paste")
			(net "FM_PE_SPRV_WAKE_N")
			(options
				(clearance outline)
				(anchor circle)
			)
			(primitives
				(gr_poly
					(pts
						(xy -0.381 -0.1524)
						(arc
							(start 0.2286 -0.1524)
							(mid 0.381 0)
							(end 0.2286 0.1524)
						)
						(xy -0.381 0.1524)
					)
					(width 0)
					(fill yes)
				)
			)
		)
		(pad "17" smd custom
			(at -3.750056 4.3688 180)
			(size 0.0762 0.0762)
			(layers "F.Cu" "F.Mask" "F.Paste")
			(net "RST_PLTRST_SPRV_R_N")
			(options
				(clearance outline)
				(anchor circle)
			)
			(primitives
				(gr_poly
					(pts
						(xy -0.1524 0.381)
						(arc
							(start -0.1524 -0.2286)
							(mid 0 -0.381)
							(end 0.1524 -0.2286)
						)
						(xy 0.1524 0.381)
					)
					(width 0)
					(fill yes)
				)
			)
		)
	)
)
